(kicad_pcb
	(version 20260206)
	(generator "pcbnew")
	(generator_version "10.0")
	(general
		(thickness 1.6)
		(legacy_teardrops no)
	)
	(paper "A4")
	(title_block
		(title "Bryce Canyon_SCC_16316-1_OCP.brd")
		(comment 1 "Bryce Canyon / footprints 436-443 of 1561")
	)
	(layers
		(0 "F.Cu" signal "TOP")
		(4 "In1.Cu" signal "L2GND")
		(6 "In2.Cu" signal "L3")
		(8 "In3.Cu" signal "L4VCC")
		(10 "In4.Cu" signal "L5VCC")
		(12 "In5.Cu" signal "L6")
		(14 "In6.Cu" signal "L7GND")
		(2 "B.Cu" signal "BOTTOM")
		(9 "F.Adhes" user "F.Adhesive")
		(11 "B.Adhes" user "B.Adhesive")
		(13 "F.Paste" user "Package Geometry/Pastemask Top")
		(15 "B.Paste" user "Package Geometry/Pastemask Bottom")
		(5 "F.SilkS" user "Ref Des/Silkscreen Top")
		(7 "B.SilkS" user "Ref Des/Silkscreen Bottom")
		(1 "F.Mask" user "Board Geometry/Soldermask Top")
		(3 "B.Mask" user "Board Geometry/Soldermask Bottom")
		(17 "Dwgs.User" user "User.Drawings")
		(19 "Cmts.User" user "User.Comments")
		(21 "Eco1.User" user "User.Eco1")
		(23 "Eco2.User" user "User.Eco2")
		(25 "Edge.Cuts" user "Board Geometry/Outline")
		(27 "Margin" user)
		(31 "F.CrtYd" user "Package Geometry/Place Bound Top")
		(29 "B.CrtYd" user "Package Geometry/Place Bound Bottom")
		(35 "F.Fab" user "Ref Des/Assembly Top")
		(33 "B.Fab" user "Ref Des/Assembly Bottom")
	)
	(footprint ""
		(layer "F.Cu")
		(at 68.838572 -100.463096 -90)
		(property "Reference" "G3"
			(at 0 0 270)
			(layer "F.SilkS")
			(hide yes)
			(effects
				(font
					(size 1.27 1.27)
				)
			)
		)
		(property "Value" "COPPER-CLOSE-GP-U"
			(at 0.0762 -2.8702 270)
			(unlocked yes)
			(layer "F.Fab")
			(hide yes)
			(effects
				(font
					(size 1.016 1.016)
					(thickness 0.1524)
				)
			)
		)
		(property "Device Type" "CON2C-U"
			(at 0.0762 -4.3942 270)
			(unlocked yes)
			(layer "F.Fab")
			(hide yes)
			(effects
				(font
					(size 1.016 1.016)
					(thickness 0.1524)
				)
			)
		)
		(duplicate_pad_numbers_are_jumpers no)
		(fp_rect
			(start -0.9398 0.9652)
			(end 0.9398 -0.9652)
			(stroke
				(width 0)
				(type default)
			)
			(fill no)
			(layer "F.CrtYd")
		)
		(fp_rect
			(start -0.9398 0.9652)
			(end 0.9398 -0.9652)
			(stroke
				(width 0)
				(type default)
			)
			(fill no)
			(layer "F.Fab")
		)
		(pad "1" smd custom
			(at 0 -0.5334 270)
			(size 0.17145 0.17145)
			(layers "F.Cu" "F.Mask" "F.Paste")
			(net "AGND_P3V3")
			(options
				(clearance outline)
				(anchor circle)
			)
			(primitives
				(gr_poly
					(pts
						(xy -0.127 0.3429) (xy -0.127 0.1651) (xy -0.635 -0.3429) (xy 0.635 -0.3429) (xy 0.127 0.1651)
						(xy 0.127 0.3429)
					)
					(width 0)
					(fill yes)
				)
			)
		)
		(pad "2" smd custom
			(at 0 0.5334 270)
			(size 0.17145 0.17145)
			(layers "F.Cu" "F.Mask" "F.Paste")
			(net "GND")
			(options
				(clearance outline)
				(anchor circle)
			)
			(primitives
				(gr_poly
					(pts
						(xy -0.635 0.3429) (xy -0.127 -0.1651) (xy -0.127 -0.3429) (xy 0.127 -0.3429) (xy 0.127 -0.1651)
						(xy 0.635 0.3429)
					)
					(width 0)
					(fill yes)
				)
			)
		)
	)
	(footprint ""
		(layer "F.Cu")
		(at 58.9788 -94.0054 -90)
		(property "Reference" "C702"
			(at 0 0 270)
			(layer "F.SilkS")
			(hide yes)
			(effects
				(font
					(size 1.27 1.27)
				)
			)
		)
		(property "Value" "SC10U16V5KX-7-GP-U"
			(at -0.0762 -6.1214 270)
			(unlocked yes)
			(layer "F.Fab")
			(hide yes)
			(effects
				(font
					(size 1.016 1.016)
					(thickness 0.1524)
				)
			)
		)
		(property "Device Type" "C805H58"
			(at -0.0762 -8.1534 270)
			(unlocked yes)
			(layer "F.Fab")
			(hide yes)
			(effects
				(font
					(size 1.016 1.016)
					(thickness 0.1524)
				)
			)
		)
		(duplicate_pad_numbers_are_jumpers no)
		(fp_line
			(start 0.635 0)
			(end -0.635 0)
			(stroke
				(width 0.508)
				(type default)
			)
			(layer "F.SilkS")
		)
		(fp_rect
			(start -0.9652 1.778)
			(end 0.9652 -1.778)
			(stroke
				(width 0)
				(type default)
			)
			(fill no)
			(layer "F.CrtYd")
		)
		(fp_poly
			(pts
				(xy -0.9652 -1.778) (xy 0.9652 -1.778) (xy 0.9652 1.778) (xy -0.9652 1.778)
			)
			(stroke
				(width 0)
				(type default)
			)
			(fill no)
			(layer "F.Fab")
		)
		(pad "1" smd rect
			(at 0 -0.9652 270)
			(size 1.397 1.143)
			(layers "F.Cu" "F.Mask" "F.Paste")
			(net "P12V_STBY_VIN_U10")
		)
		(pad "2" smd rect
			(at 0 0.9652 270)
			(size 1.397 1.143)
			(layers "F.Cu" "F.Mask" "F.Paste")
			(net "GND")
		)
	)
	(footprint ""
		(layer "F.Cu")
		(at 101.6762 -87.2236 180)
		(property "Reference" "R73"
			(at 0 0 180)
			(layer "F.SilkS")
			(hide yes)
			(effects
				(font
					(size 1.27 1.27)
				)
			)
		)
		(property "Value" "4K7R2F-GP"
			(at 0.064008 -3.993896 180)
			(unlocked yes)
			(layer "F.Fab")
			(hide yes)
			(effects
				(font
					(size 1.016 1.016)
					(thickness 0.1524)
				)
			)
		)
		(property "Device Type" "R402H16"
			(at 0.064008 -5.517896 180)
			(unlocked yes)
			(layer "F.Fab")
			(hide yes)
			(effects
				(font
					(size 1.016 1.016)
					(thickness 0.1524)
				)
			)
		)
		(duplicate_pad_numbers_are_jumpers no)
		(fp_line
			(start 0.508 -0.9398)
			(end -0.508 -0.9398)
			(stroke
				(width 0.1524)
				(type default)
			)
			(layer "F.SilkS")
		)
		(fp_line
			(start -0.508 -0.9398)
			(end -0.508 0.9398)
			(stroke
				(width 0.1524)
				(type default)
			)
			(layer "F.SilkS")
		)
		(fp_rect
			(start -0.508 0.9398)
			(end 0.508 -0.9398)
			(stroke
				(width 0)
				(type default)
			)
			(fill no)
			(layer "F.CrtYd")
		)
		(fp_rect
			(start -0.508 0.9398)
			(end 0.508 -0.9398)
			(stroke
				(width 0)
				(type default)
			)
			(fill no)
			(layer "F.Fab")
		)
		(pad "1" smd custom
			(at 0 -0.4445 180)
			(size 0.1397 0.1397)
			(layers "F.Cu" "F.Mask" "F.Paste")
			(net "P1V8_E")
			(options
				(clearance outline)
				(anchor circle)
			)
			(primitives
				(gr_poly
					(pts
						(arc
							(start -0.1778 -0.2794)
							(mid -0.249642 -0.249642)
							(end -0.2794 -0.1778)
						)
						(arc
							(start -0.2794 0.1778)
							(mid -0.249642 0.249642)
							(end -0.1778 0.2794)
						)
						(arc
							(start 0.1778 0.2794)
							(mid 0.249642 0.249642)
							(end 0.2794 0.1778)
						)
						(arc
							(start 0.2794 -0.1778)
							(mid 0.249642 -0.249642)
							(end 0.1778 -0.2794)
						)
					)
					(width 0)
					(fill yes)
				)
			)
		)
		(pad "2" smd custom
			(at 0 0.4445 180)
			(size 0.1397 0.1397)
			(layers "F.Cu" "F.Mask" "F.Paste")
			(net "SCC_TYPE_1_LS")
			(options
				(clearance outline)
				(anchor circle)
			)
			(primitives
				(gr_poly
					(pts
						(arc
							(start -0.1778 -0.2794)
							(mid -0.249642 -0.249642)
							(end -0.2794 -0.1778)
						)
						(arc
							(start -0.2794 0.1778)
							(mid -0.249642 0.249642)
							(end -0.1778 0.2794)
						)
						(arc
							(start 0.1778 0.2794)
							(mid 0.249642 0.249642)
							(end 0.2794 0.1778)
						)
						(arc
							(start 0.2794 -0.1778)
							(mid 0.249642 -0.249642)
							(end 0.1778 -0.2794)
						)
					)
					(width 0)
					(fill yes)
				)
			)
		)
	)
	(footprint ""
		(layer "F.Cu")
		(at 92.583 -75.9968 90)
		(property "Reference" "R123"
			(at 0 0 90)
			(layer "F.SilkS")
			(hide yes)
			(effects
				(font
					(size 1.27 1.27)
				)
			)
		)
		(property "Value" "4K75R2F-1-GP"
			(at 0.064008 -3.993896 90)
			(unlocked yes)
			(layer "F.Fab")
			(hide yes)
			(effects
				(font
					(size 1.016 1.016)
					(thickness 0.1524)
				)
			)
		)
		(property "Device Type" "R402H16"
			(at 0.064008 -5.517896 90)
			(unlocked yes)
			(layer "F.Fab")
			(hide yes)
			(effects
				(font
					(size 1.016 1.016)
					(thickness 0.1524)
				)
			)
		)
		(duplicate_pad_numbers_are_jumpers no)
		(fp_line
			(start 0.508 -0.9398)
			(end -0.508 -0.9398)
			(stroke
				(width 0.1524)
				(type default)
			)
			(layer "F.SilkS")
		)
		(fp_line
			(start -0.508 -0.9398)
			(end -0.508 0.9398)
			(stroke
				(width 0.1524)
				(type default)
			)
			(layer "F.SilkS")
		)
		(fp_rect
			(start -0.508 0.9398)
			(end 0.508 -0.9398)
			(stroke
				(width 0)
				(type default)
			)
			(fill no)
			(layer "F.CrtYd")
		)
		(fp_rect
			(start -0.508 0.9398)
			(end 0.508 -0.9398)
			(stroke
				(width 0)
				(type default)
			)
			(fill no)
			(layer "F.Fab")
		)
		(pad "1" smd custom
			(at 0 -0.4445 90)
			(size 0.1397 0.1397)
			(layers "F.Cu" "F.Mask" "F.Paste")
			(net "P1V8_E")
			(options
				(clearance outline)
				(anchor circle)
			)
			(primitives
				(gr_poly
					(pts
						(arc
							(start -0.1778 -0.2794)
							(mid -0.249642 -0.249642)
							(end -0.2794 -0.1778)
						)
						(arc
							(start -0.2794 0.1778)
							(mid -0.249642 0.249642)
							(end -0.1778 0.2794)
						)
						(arc
							(start 0.1778 0.2794)
							(mid 0.249642 0.249642)
							(end 0.2794 0.1778)
						)
						(arc
							(start 0.2794 -0.1778)
							(mid 0.249642 -0.249642)
							(end 0.1778 -0.2794)
						)
					)
					(width 0)
					(fill yes)
				)
			)
		)
		(pad "2" smd custom
			(at 0 0.4445 90)
			(size 0.1397 0.1397)
			(layers "F.Cu" "F.Mask" "F.Paste")
			(net "EXP_CLK_SEL0")
			(options
				(clearance outline)
				(anchor circle)
			)
			(primitives
				(gr_poly
					(pts
						(arc
							(start -0.1778 -0.2794)
							(mid -0.249642 -0.249642)
							(end -0.2794 -0.1778)
						)
						(arc
							(start -0.2794 0.1778)
							(mid -0.249642 0.249642)
							(end -0.1778 0.2794)
						)
						(arc
							(start 0.1778 0.2794)
							(mid 0.249642 0.249642)
							(end 0.2794 0.1778)
						)
						(arc
							(start 0.2794 -0.1778)
							(mid 0.249642 -0.249642)
							(end 0.1778 -0.2794)
						)
					)
					(width 0)
					(fill yes)
				)
			)
		)
	)
	(footprint ""
		(layer "F.Cu")
		(at 75.311 -46.5582)
		(property "Reference" "C296"
			(at 0 0 0)
			(layer "F.SilkS")
			(hide yes)
			(effects
				(font
					(size 1.27 1.27)
				)
			)
		)
		(property "Value" "SC22U6D3V3MX-9-GP-U"
			(at 0 -2.8194 0)
			(unlocked yes)
			(layer "F.Fab")
			(hide yes)
			(effects
				(font
					(size 1.016 1.016)
					(thickness 0.1524)
				)
			)
		)
		(property "Device Type" "C603H40"
			(at 0 -4.3434 0)
			(unlocked yes)
			(layer "F.Fab")
			(hide yes)
			(effects
				(font
					(size 1.016 1.016)
					(thickness 0.1524)
				)
			)
		)
		(duplicate_pad_numbers_are_jumpers no)
		(fp_line
			(start 0.508 0)
			(end -0.508 0)
			(stroke
				(width 0.2032)
				(type default)
			)
			(layer "F.SilkS")
		)
		(fp_rect
			(start -0.5842 1.3335)
			(end 0.5842 -1.3335)
			(stroke
				(width 0)
				(type default)
			)
			(fill no)
			(layer "F.CrtYd")
		)
		(fp_rect
			(start -0.5842 1.3335)
			(end 0.5842 -1.3335)
			(stroke
				(width 0)
				(type default)
			)
			(fill no)
			(layer "F.Fab")
		)
		(pad "1" smd custom
			(at 0 -0.762)
			(size 0.2159 0.2159)
			(layers "F.Cu" "F.Mask" "F.Paste")
			(net "GB_VDDA")
			(options
				(clearance outline)
				(anchor circle)
			)
			(primitives
				(gr_poly
					(pts
						(arc
							(start -0.3302 -0.4318)
							(mid -0.402042 -0.402042)
							(end -0.4318 -0.3302)
						)
						(arc
							(start -0.4318 0.3302)
							(mid -0.402042 0.402042)
							(end -0.3302 0.4318)
						)
						(arc
							(start 0.3302 0.4318)
							(mid 0.402042 0.402042)
							(end 0.4318 0.3302)
						)
						(arc
							(start 0.4318 -0.3302)
							(mid 0.402042 -0.402042)
							(end 0.3302 -0.4318)
						)
					)
					(width 0)
					(fill yes)
				)
			)
		)
		(pad "2" smd custom
			(at 0 0.762)
			(size 0.2159 0.2159)
			(layers "F.Cu" "F.Mask" "F.Paste")
			(net "GND")
			(options
				(clearance outline)
				(anchor circle)
			)
			(primitives
				(gr_poly
					(pts
						(arc
							(start -0.3302 -0.4318)
							(mid -0.402042 -0.402042)
							(end -0.4318 -0.3302)
						)
						(arc
							(start -0.4318 0.3302)
							(mid -0.402042 0.402042)
							(end -0.3302 0.4318)
						)
						(arc
							(start 0.3302 0.4318)
							(mid 0.402042 0.402042)
							(end 0.4318 0.3302)
						)
						(arc
							(start 0.4318 -0.3302)
							(mid 0.402042 -0.402042)
							(end 0.3302 -0.4318)
						)
					)
					(width 0)
					(fill yes)
				)
			)
		)
	)
	(footprint ""
		(layer "F.Cu")
		(at 15.3416 -93.5736)
		(property "Reference" "R431"
			(at 0 0 0)
			(layer "F.SilkS")
			(hide yes)
			(effects
				(font
					(size 1.27 1.27)
				)
			)
		)
		(property "Value" "1KR2F-3-GP"
			(at 0.064008 -3.993896 0)
			(unlocked yes)
			(layer "F.Fab")
			(hide yes)
			(effects
				(font
					(size 1.016 1.016)
					(thickness 0.1524)
				)
			)
		)
		(property "Device Type" "R402H16"
			(at 0.064008 -5.517896 0)
			(unlocked yes)
			(layer "F.Fab")
			(hide yes)
			(effects
				(font
					(size 1.016 1.016)
					(thickness 0.1524)
				)
			)
		)
		(duplicate_pad_numbers_are_jumpers no)
		(fp_line
			(start -0.508 -0.9398)
			(end -0.508 0.9398)
			(stroke
				(width 0.1524)
				(type default)
			)
			(layer "F.SilkS")
		)
		(fp_line
			(start 0.508 -0.9398)
			(end -0.508 -0.9398)
			(stroke
				(width 0.1524)
				(type default)
			)
			(layer "F.SilkS")
		)
		(fp_rect
			(start -0.508 0.9398)
			(end 0.508 -0.9398)
			(stroke
				(width 0)
				(type default)
			)
			(fill no)
			(layer "F.CrtYd")
		)
		(fp_rect
			(start -0.508 0.9398)
			(end 0.508 -0.9398)
			(stroke
				(width 0)
				(type default)
			)
			(fill no)
			(layer "F.Fab")
		)
		(pad "1" smd custom
			(at 0 -0.4445)
			(size 0.1397 0.1397)
			(layers "F.Cu" "F.Mask" "F.Paste")
			(net "P3V3")
			(options
				(clearance outline)
				(anchor circle)
			)
			(primitives
				(gr_poly
					(pts
						(arc
							(start -0.1778 -0.2794)
							(mid -0.249642 -0.249642)
							(end -0.2794 -0.1778)
						)
						(arc
							(start -0.2794 0.1778)
							(mid -0.249642 0.249642)
							(end -0.1778 0.2794)
						)
						(arc
							(start 0.1778 0.2794)
							(mid 0.249642 0.249642)
							(end 0.2794 0.1778)
						)
						(arc
							(start 0.2794 -0.1778)
							(mid 0.249642 -0.249642)
							(end 0.1778 -0.2794)
						)
					)
					(width 0)
					(fill yes)
				)
			)
		)
		(pad "2" smd custom
			(at 0 0.4445)
			(size 0.1397 0.1397)
			(layers "F.Cu" "F.Mask" "F.Paste")
			(net "I2C_DPB_SDA3")
			(options
				(clearance outline)
				(anchor circle)
			)
			(primitives
				(gr_poly
					(pts
						(arc
							(start -0.1778 -0.2794)
							(mid -0.249642 -0.249642)
							(end -0.2794 -0.1778)
						)
						(arc
							(start -0.2794 0.1778)
							(mid -0.249642 0.249642)
							(end -0.1778 0.2794)
						)
						(arc
							(start 0.1778 0.2794)
							(mid 0.249642 0.249642)
							(end 0.2794 0.1778)
						)
						(arc
							(start 0.2794 -0.1778)
							(mid 0.249642 -0.249642)
							(end 0.1778 -0.2794)
						)
					)
					(width 0)
					(fill yes)
				)
			)
		)
	)
	(footprint ""
		(layer "F.Cu")
		(at 61.0108 -77.4954 180)
		(property "Reference" "R437"
			(at 0 0 180)
			(layer "F.SilkS")
			(hide yes)
			(effects
				(font
					(size 1.27 1.27)
				)
			)
		)
		(property "Value" "200KR2F-L-GP"
			(at 0.064008 -3.993896 180)
			(unlocked yes)
			(layer "F.Fab")
			(hide yes)
			(effects
				(font
					(size 1.016 1.016)
					(thickness 0.1524)
				)
			)
		)
		(property "Device Type" "R402H16"
			(at 0.064008 -5.517896 180)
			(unlocked yes)
			(layer "F.Fab")
			(hide yes)
			(effects
				(font
					(size 1.016 1.016)
					(thickness 0.1524)
				)
			)
		)
		(duplicate_pad_numbers_are_jumpers no)
		(fp_line
			(start 0.508 -0.9398)
			(end -0.508 -0.9398)
			(stroke
				(width 0.1524)
				(type default)
			)
			(layer "F.SilkS")
		)
		(fp_line
			(start -0.508 -0.9398)
			(end -0.508 0.9398)
			(stroke
				(width 0.1524)
				(type default)
			)
			(layer "F.SilkS")
		)
		(fp_rect
			(start -0.508 0.9398)
			(end 0.508 -0.9398)
			(stroke
				(width 0)
				(type default)
			)
			(fill no)
			(layer "F.CrtYd")
		)
		(fp_rect
			(start -0.508 0.9398)
			(end 0.508 -0.9398)
			(stroke
				(width 0)
				(type default)
			)
			(fill no)
			(layer "F.Fab")
		)
		(pad "1" smd custom
			(at 0 -0.4445 180)
			(size 0.1397 0.1397)
			(layers "F.Cu" "F.Mask" "F.Paste")
			(net "LS_EN_U37")
			(options
				(clearance outline)
				(anchor circle)
			)
			(primitives
				(gr_poly
					(pts
						(arc
							(start -0.1778 -0.2794)
							(mid -0.249642 -0.249642)
							(end -0.2794 -0.1778)
						)
						(arc
							(start -0.2794 0.1778)
							(mid -0.249642 0.249642)
							(end -0.1778 0.2794)
						)
						(arc
							(start 0.1778 0.2794)
							(mid 0.249642 0.249642)
							(end 0.2794 0.1778)
						)
						(arc
							(start 0.2794 -0.1778)
							(mid 0.249642 -0.249642)
							(end 0.1778 -0.2794)
						)
					)
					(width 0)
					(fill yes)
				)
			)
		)
		(pad "2" smd custom
			(at 0 0.4445 180)
			(size 0.1397 0.1397)
			(layers "F.Cu" "F.Mask" "F.Paste")
			(net "P0V9_PG")
			(options
				(clearance outline)
				(anchor circle)
			)
			(primitives
				(gr_poly
					(pts
						(arc
							(start -0.1778 -0.2794)
							(mid -0.249642 -0.249642)
							(end -0.2794 -0.1778)
						)
						(arc
							(start -0.2794 0.1778)
							(mid -0.249642 0.249642)
							(end -0.1778 0.2794)
						)
						(arc
							(start 0.1778 0.2794)
							(mid 0.249642 0.249642)
							(end 0.2794 0.1778)
						)
						(arc
							(start 0.2794 -0.1778)
							(mid 0.249642 -0.249642)
							(end 0.1778 -0.2794)
						)
					)
					(width 0)
					(fill yes)
				)
			)
		)
	)
	(footprint ""
		(layer "F.Cu")
		(at 191.85382 -53.3908 90)
		(property "Reference" "R225"
			(at 0 0 90)
			(layer "F.SilkS")
			(hide yes)
			(effects
				(font
					(size 1.27 1.27)
				)
			)
		)
		(property "Value" "10KR2F-2-GP"
			(at 0.064008 -3.993896 90)
			(unlocked yes)
			(layer "F.Fab")
			(hide yes)
			(effects
				(font
					(size 1.016 1.016)
					(thickness 0.1524)
				)
			)
		)
		(property "Device Type" "R402H16"
			(at 0.064008 -5.517896 90)
			(unlocked yes)
			(layer "F.Fab")
			(hide yes)
			(effects
				(font
					(size 1.016 1.016)
					(thickness 0.1524)
				)
			)
		)
		(duplicate_pad_numbers_are_jumpers no)
		(fp_line
			(start 0.508 -0.9398)
			(end -0.508 -0.9398)
			(stroke
				(width 0.1524)
				(type default)
			)
			(layer "F.SilkS")
		)
		(fp_line
			(start -0.508 -0.9398)
			(end -0.508 0.9398)
			(stroke
				(width 0.1524)
				(type default)
			)
			(layer "F.SilkS")
		)
		(fp_rect
			(start -0.508 0.9398)
			(end 0.508 -0.9398)
			(stroke
				(width 0)
				(type default)
			)
			(fill no)
			(layer "F.CrtYd")
		)
		(fp_rect
			(start -0.508 0.9398)
			(end 0.508 -0.9398)
			(stroke
				(width 0)
				(type default)
			)
			(fill no)
			(layer "F.Fab")
		)
		(pad "1" smd custom
			(at 0 -0.4445 90)
			(size 0.1397 0.1397)
			(layers "F.Cu" "F.Mask" "F.Paste")
			(net "XM_ADDR_5")
			(options
				(clearance outline)
				(anchor circle)
			)
			(primitives
				(gr_poly
					(pts
						(arc
							(start -0.1778 -0.2794)
							(mid -0.249642 -0.249642)
							(end -0.2794 -0.1778)
						)
						(arc
							(start -0.2794 0.1778)
							(mid -0.249642 0.249642)
							(end -0.1778 0.2794)
						)
						(arc
							(start 0.1778 0.2794)
							(mid 0.249642 0.249642)
							(end 0.2794 0.1778)
						)
						(arc
							(start 0.2794 -0.1778)
							(mid 0.249642 -0.249642)
							(end 0.1778 -0.2794)
						)
					)
					(width 0)
					(fill yes)
				)
			)
		)
		(pad "2" smd custom
			(at 0 0.4445 90)
			(size 0.1397 0.1397)
			(layers "F.Cu" "F.Mask" "F.Paste")
			(net "GND")
			(options
				(clearance outline)
				(anchor circle)
			)
			(primitives
				(gr_poly
					(pts
						(arc
							(start -0.1778 -0.2794)
							(mid -0.249642 -0.249642)
							(end -0.2794 -0.1778)
						)
						(arc
							(start -0.2794 0.1778)
							(mid -0.249642 0.249642)
							(end -0.1778 0.2794)
						)
						(arc
							(start 0.1778 0.2794)
							(mid 0.249642 0.249642)
							(end 0.2794 0.1778)
						)
						(arc
							(start 0.2794 -0.1778)
							(mid 0.249642 -0.249642)
							(end 0.1778 -0.2794)
						)
					)
					(width 0)
					(fill yes)
				)
			)
		)
	)
)
